# T6G (Grand Teton) — schematic netlist excerpt (pin names and nets, part order shuffled) for the footprints in the layout excerpt that follows; sources: Cadence DE-HDL packaged netlist, KiCad conversion of 04192023_DAF0TMB3IC0_F0TG_MB_C_brd_V02_OCP.brd

C615  Q_CAP  0.1UF 10V 10% X7S  pkg C0201  page 290 : A = P0V9_CPU0_RT_2D ; B = GND
R6236  Q_RES  10K 1% EMPTY  pkg 0402LF  page 267 : A = P3V3_AUX ; B = A_HSC_LOW_GATE

Q81  MOSFET_NCH_DUAL  PJT138K IC  pkg SOT363XD  page 255
  S1  = GND
  G1  = FM_LED_PWRGD_PVDDIO_P0
  D2  = LED_PWRGD_PVDD11_S3_P0_D
  S2  = GND
  G2  = FM_LED_PWRGD_PVDD11_S3_P0
  D1  = LED_PWRGD_PVDDIO_P0_D

(kicad_pcb
	(version 20260206)
	(generator "pcbnew")
	(generator_version "10.0")
	(general
		(thickness 1.6)
		(legacy_teardrops no)
	)
	(paper "A4")
	(title_block
		(title "04192023_DAF0TMB3IC0_F0TG_MB_C_brd_V02_OCP.brd")
		(comment 1 "Grand Teton / footprints 7850-7852 of 8354")
	)
	(layers
		(0 "F.Cu" signal "TOP")
		(4 "In1.Cu" signal "GND")
		(6 "In2.Cu" signal "IN1")
		(8 "In3.Cu" signal "GND1")
		(10 "In4.Cu" signal "IN2")
		(12 "In5.Cu" signal "GND2")
		(14 "In6.Cu" signal "IN3")
		(16 "In7.Cu" signal "GND3")
		(18 "In8.Cu" signal "VCC")
		(20 "In9.Cu" signal "VCC1")
		(22 "In10.Cu" signal "GND4")
		(24 "In11.Cu" signal "IN4")
		(26 "In12.Cu" signal "GND5")
		(28 "In13.Cu" signal "IN5")
		(30 "In14.Cu" signal "GND6")
		(32 "In15.Cu" signal "IN6")
		(34 "In16.Cu" signal "GND7")
		(2 "B.Cu" signal "BOTTOM")
		(9 "F.Adhes" user "F.Adhesive")
		(11 "B.Adhes" user "B.Adhesive")
		(13 "F.Paste" user "Package Geometry/Pastemask Top")
		(15 "B.Paste" user "Package Geometry/Pastemask Bottom")
		(5 "F.SilkS" user "Ref Des/Silkscreen Top")
		(7 "B.SilkS" user "Ref Des/Silkscreen Bottom")
		(1 "F.Mask" user "Board Geometry/Soldermask Top")
		(3 "B.Mask" user "Board Geometry/Soldermask Bottom")
		(17 "Dwgs.User" user "User.Drawings")
		(19 "Cmts.User" user "User.Comments")
		(21 "Eco1.User" user "User.Eco1")
		(23 "Eco2.User" user "User.Eco2")
		(25 "Edge.Cuts" user "Board Geometry/Outline")
		(27 "Margin" user)
		(31 "F.CrtYd" user "Package Geometry/Place Bound Top")
		(29 "B.CrtYd" user "Package Geometry/Place Bound Bottom")
		(35 "F.Fab" user "Ref Des/Assembly Top")
		(33 "B.Fab" user "Ref Des/Assembly Bottom")
	)
	(footprint ""
		(layer "B.Cu")
		(at 348.04604 -396.393162 -90)
		(property "Reference" "C615"
			(at 0 0 90)
			(layer "B.SilkS")
			(hide yes)
			(effects
				(font
					(size 1.27 1.27)
				)
				(justify mirror)
			)
		)
		(property "Value" ""
			(at 0 0 90)
			(layer "B.Fab")
			(effects
				(font
					(size 1.27 1.27)
				)
				(justify mirror)
			)
		)
		(duplicate_pad_numbers_are_jumpers no)
		(fp_line
			(start -0.299974 0.150114)
			(end 0.299974 0.150114)
			(stroke
				(width 0.1)
				(type default)
			)
			(layer "B.Fab")
		)
		(fp_line
			(start 0.299974 0.150114)
			(end 0.299974 -0.150114)
			(stroke
				(width 0.1)
				(type default)
			)
			(layer "B.Fab")
		)
		(fp_line
			(start -0.299974 -0.150114)
			(end -0.299974 0.150114)
			(stroke
				(width 0.1)
				(type default)
			)
			(layer "B.Fab")
		)
		(fp_line
			(start 0.299974 -0.150114)
			(end -0.299974 -0.150114)
			(stroke
				(width 0.1)
				(type default)
			)
			(layer "B.Fab")
		)
		(pad "1" smd rect
			(at 0.2667 0 90)
			(size 0.3048 0.381)
			(layers "B.Cu" "B.Mask" "B.Paste")
			(net "P0V9_CPU0_RT_2D")
		)
		(pad "2" smd rect
			(at -0.2667 0 90)
			(size 0.3048 0.381)
			(layers "B.Cu" "B.Mask" "B.Paste")
			(net "GND")
		)
	)
	(footprint ""
		(layer "B.Cu")
		(at 332.464664 -73.534778)
		(property "Reference" "Q81"
			(at 1.4859 2.394712 0)
			(unlocked yes)
			(layer "B.SilkS")
			(effects
				(font
					(size 0.7874 0.5842)
					(thickness 0.1524)
				)
				(justify left mirror)
			)
		)
		(property "Value" ""
			(at 0 0 0)
			(layer "B.Fab")
			(effects
				(font
					(size 1.27 1.27)
				)
				(justify mirror)
			)
		)
		(duplicate_pad_numbers_are_jumpers no)
		(fp_line
			(start -1.332738 -1.100074)
			(end -1.332738 1.100074)
			(stroke
				(width 0.1524)
				(type default)
			)
			(layer "B.SilkS")
		)
		(fp_line
			(start -1.332738 1.100074)
			(end 1.332738 1.100074)
			(stroke
				(width 0.1524)
				(type default)
			)
			(layer "B.SilkS")
		)
		(fp_line
			(start -0.4826 -1.100074)
			(end -1.332738 -1.100074)
			(stroke
				(width 0.1524)
				(type default)
			)
			(layer "B.SilkS")
		)
		(fp_line
			(start 0 -0.541274)
			(end -0.4826 -1.100074)
			(stroke
				(width 0.1524)
				(type default)
			)
			(layer "B.SilkS")
		)
		(fp_line
			(start 0.4826 -1.100074)
			(end 0 -0.541274)
			(stroke
				(width 0.1524)
				(type default)
			)
			(layer "B.SilkS")
		)
		(fp_line
			(start 1.332738 -1.100074)
			(end 0.4826 -1.100074)
			(stroke
				(width 0.1524)
				(type default)
			)
			(layer "B.SilkS")
		)
		(fp_line
			(start 1.332738 1.100074)
			(end 1.332738 -1.100074)
			(stroke
				(width 0.1524)
				(type default)
			)
			(layer "B.SilkS")
		)
		(fp_poly
			(pts
				(xy 1.533144 -0.649986) (xy 2.2352 -1.001014) (xy 2.2352 -0.298958)
			)
			(stroke
				(width 0)
				(type default)
			)
			(fill yes)
			(layer "B.SilkS")
		)
		(fp_line
			(start -0.674878 -1.100074)
			(end -0.674878 1.100074)
			(stroke
				(width 0.1)
				(type default)
			)
			(layer "B.Fab")
		)
		(fp_line
			(start -0.674878 1.100074)
			(end 0.674878 1.100074)
			(stroke
				(width 0.1)
				(type default)
			)
			(layer "B.Fab")
		)
		(fp_line
			(start 0.674878 -1.100074)
			(end -0.674878 -1.100074)
			(stroke
				(width 0.1)
				(type default)
			)
			(layer "B.Fab")
		)
		(fp_line
			(start 0.674878 1.100074)
			(end 0.674878 -1.100074)
			(stroke
				(width 0.1)
				(type default)
			)
			(layer "B.Fab")
		)
		(fp_poly
			(pts
				(xy 2.2352 -0.298958) (xy 2.2352 -1.001014) (xy 1.533144 -0.649986)
			)
			(stroke
				(width 0)
				(type default)
			)
			(fill yes)
			(layer "B.Fab")
		)
		(pad "1" smd rect
			(at 0.94996 -0.649986 90)
			(size 0.4318 0.508)
			(layers "B.Cu" "B.Mask" "B.Paste")
			(net "GND")
		)
		(pad "2" smd rect
			(at 0.94996 0 90)
			(size 0.4318 0.508)
			(layers "B.Cu" "B.Mask" "B.Paste")
			(net "FM_LED_PWRGD_PVDDIO_P0")
		)
		(pad "3" smd rect
			(at 0.94996 0.649986 90)
			(size 0.4318 0.508)
			(layers "B.Cu" "B.Mask" "B.Paste")
			(net "LED_PWRGD_PVDD11_S3_P0_D")
		)
		(pad "4" smd rect
			(at -0.94996 0.649986 90)
			(size 0.4318 0.508)
			(layers "B.Cu" "B.Mask" "B.Paste")
			(net "GND")
		)
		(pad "5" smd rect
			(at -0.94996 0 90)
			(size 0.4318 0.508)
			(layers "B.Cu" "B.Mask" "B.Paste")
			(net "FM_LED_PWRGD_PVDD11_S3_P0")
		)
		(pad "6" smd rect
			(at -0.94996 -0.649986 90)
			(size 0.4318 0.508)
			(layers "B.Cu" "B.Mask" "B.Paste")
			(net "LED_PWRGD_PVDDIO_P0_D")
		)
	)
	(footprint ""
		(layer "B.Cu")
		(at 171.976288 -427.923706 180)
		(property "Reference" "R6236"
			(at 0 0 0)
			(layer "B.SilkS")
			(hide yes)
			(effects
				(font
					(size 1.27 1.27)
				)
				(justify mirror)
			)
		)
		(property "Value" ""
			(at 0 0 0)
			(layer "B.Fab")
			(effects
				(font
					(size 1.27 1.27)
				)
				(justify mirror)
			)
		)
		(duplicate_pad_numbers_are_jumpers no)
		(fp_line
			(start 0.7874 0.4064)
			(end 0.7874 -0.4064)
			(stroke
				(width 0.1524)
				(type default)
			)
			(layer "B.SilkS")
		)
		(fp_line
			(start 0.7874 -0.4064)
			(end -0.7874 -0.4064)
			(stroke
				(width 0.1524)
				(type default)
			)
			(layer "B.SilkS")
		)
		(fp_line
			(start -0.7874 0.4064)
			(end 0.7874 0.4064)
			(stroke
				(width 0.1524)
				(type default)
			)
			(layer "B.SilkS")
		)
		(fp_line
			(start -0.7874 -0.4064)
			(end -0.7874 0.4064)
			(stroke
				(width 0.1524)
				(type default)
			)
			(layer "B.SilkS")
		)
		(fp_line
			(start 0.67945 0.3048)
			(end 0.67945 -0.305054)
			(stroke
				(width 0.1)
				(type default)
			)
			(layer "B.Fab")
		)
		(fp_line
			(start 0.67945 -0.305054)
			(end 0.12065 -0.305054)
			(stroke
				(width 0.1)
				(type default)
			)
			(layer "B.Fab")
		)
		(fp_line
			(start 0.12065 0.3048)
			(end 0.67945 0.3048)
			(stroke
				(width 0.1)
				(type default)
			)
			(layer "B.Fab")
		)
		(fp_line
			(start 0.12065 0.2794)
			(end 0.12065 0.3048)
			(stroke
				(width 0.1)
				(type default)
			)
			(layer "B.Fab")
		)
		(fp_line
			(start 0.12065 -0.2794)
			(end -0.12065 -0.2794)
			(stroke
				(width 0.1)
				(type default)
			)
			(layer "B.Fab")
		)
		(fp_line
			(start 0.12065 -0.305054)
			(end 0.12065 -0.2794)
			(stroke
				(width 0.1)
				(type default)
			)
			(layer "B.Fab")
		)
		(fp_line
			(start -0.120396 0.3048)
			(end -0.120396 0.2794)
			(stroke
				(width 0.1)
				(type default)
			)
			(layer "B.Fab")
		)
		(fp_line
			(start -0.120396 0.2794)
			(end 0.12065 0.2794)
			(stroke
				(width 0.1)
				(type default)
			)
			(layer "B.Fab")
		)
		(fp_line
			(start -0.12065 -0.2794)
			(end -0.12065 -0.3048)
			(stroke
				(width 0.1)
				(type default)
			)
			(layer "B.Fab")
		)
		(fp_line
			(start -0.12065 -0.3048)
			(end -0.67945 -0.3048)
			(stroke
				(width 0.1)
				(type default)
			)
			(layer "B.Fab")
		)
		(fp_line
			(start -0.67945 0.3048)
			(end -0.120396 0.3048)
			(stroke
				(width 0.1)
				(type default)
			)
			(layer "B.Fab")
		)
		(fp_line
			(start -0.67945 -0.3048)
			(end -0.67945 0.3048)
			(stroke
				(width 0.1)
				(type default)
			)
			(layer "B.Fab")
		)
		(pad "1" smd circle
			(at 0.40005 0)
			(size 0 0)
			(layers "B.Cu" "B.Mask" "B.Paste")
			(net "P3V3_AUX")
		)
		(pad "2" smd circle
			(at -0.40005 0)
			(size 0 0)
			(layers "B.Cu" "B.Mask" "B.Paste")
			(net "A_HSC_LOW_GATE")
		)
	)
)
